(kicad_pcb
	(version 20260206)
	(generator "pcbnew")
	(generator_version "10.0")
	(general
		(thickness 1.6)
		(legacy_teardrops no)
	)
	(paper "A4")
	(title_block
		(title "v1-chassis-manager — T6M_CM_d_v01_1031_1645.brd")
		(comment 1 "Open CloudServer (Microsoft) / footprints 2223-2232 of 2512")
	)
	(layers
		(0 "F.Cu" signal "TOP")
		(4 "In1.Cu" signal "GND1")
		(6 "In2.Cu" signal "IN1")
		(8 "In3.Cu" signal "VCC1")
		(10 "In4.Cu" signal "VCC2")
		(12 "In5.Cu" signal "GND2")
		(14 "In6.Cu" signal "IN2")
		(16 "In7.Cu" signal "IN3")
		(18 "In8.Cu" signal "GND3")
		(2 "B.Cu" signal "BOTTOM")
		(9 "F.Adhes" user "F.Adhesive")
		(11 "B.Adhes" user "B.Adhesive")
		(13 "F.Paste" user "Package Geometry/Pastemask Top")
		(15 "B.Paste" user "Package Geometry/Pastemask Bottom")
		(5 "F.SilkS" user "Ref Des/Silkscreen Top")
		(7 "B.SilkS" user "Ref Des/Silkscreen Bottom")
		(1 "F.Mask" user "Board Geometry/Soldermask Top")
		(3 "B.Mask" user "Board Geometry/Soldermask Bottom")
		(17 "Dwgs.User" user "User.Drawings")
		(19 "Cmts.User" user "User.Comments")
		(21 "Eco1.User" user "User.Eco1")
		(23 "Eco2.User" user "User.Eco2")
		(25 "Edge.Cuts" user "Board Geometry/Outline")
		(27 "Margin" user)
		(31 "F.CrtYd" user "Package Geometry/Place Bound Top")
		(29 "B.CrtYd" user "Package Geometry/Place Bound Bottom")
		(35 "F.Fab" user "Ref Des/Assembly Top")
		(33 "B.Fab" user "Ref Des/Assembly Bottom")
	)
	(footprint ""
		(layer "B.Cu")
		(at 155.661614 -62.075822 90)
		(property "Reference" "L32"
			(at -2.829814 6.138418 270)
			(unlocked yes)
			(layer "B.SilkS")
			(effects
				(font
					(size 0.7874 0.5842)
					(thickness 0.1524)
				)
				(justify left mirror)
			)
		)
		(property "Value" ""
			(at 0 0 90)
			(layer "B.Fab")
			(effects
				(font
					(size 1.27 1.27)
				)
				(justify mirror)
			)
		)
		(duplicate_pad_numbers_are_jumpers no)
		(fp_line
			(start 0.7874 -0.4064)
			(end -0.7874 -0.4064)
			(stroke
				(width 0.1524)
				(type default)
			)
			(layer "B.SilkS")
		)
		(fp_line
			(start -0.7874 -0.4064)
			(end -0.7874 0.4064)
			(stroke
				(width 0.1524)
				(type default)
			)
			(layer "B.SilkS")
		)
		(fp_line
			(start 0.7874 0.4064)
			(end 0.7874 -0.4064)
			(stroke
				(width 0.1524)
				(type default)
			)
			(layer "B.SilkS")
		)
		(fp_line
			(start 0.0889 0.4064)
			(end 0.0889 -0.4064)
			(stroke
				(width 0.1524)
				(type default)
			)
			(layer "B.SilkS")
		)
		(fp_line
			(start -0.0889 0.4064)
			(end -0.0889 -0.4064)
			(stroke
				(width 0.1524)
				(type default)
			)
			(layer "B.SilkS")
		)
		(fp_line
			(start -0.7874 0.4064)
			(end 0.7874 0.4064)
			(stroke
				(width 0.1524)
				(type default)
			)
			(layer "B.SilkS")
		)
		(fp_poly
			(pts
				(xy 0.5334 0.254) (xy 0.635 0.254) (xy 0.635 0.2286) (xy 0.635 -0.254) (xy 0.5334 -0.254) (xy 0.5334 -0.2794)
				(xy -0.5334 -0.2794) (xy -0.5334 -0.254) (xy -0.635 -0.254) (xy -0.635 0.254) (xy -0.5334 0.254)
				(xy -0.5334 0.2794) (xy 0.508 0.2794) (xy 0.5334 0.2794)
			)
			(stroke
				(width 0)
				(type default)
			)
			(fill no)
			(layer "B.CrtYd")
		)
		(pad "1" smd rect
			(at -0.40005 0 270)
			(size 0.4572 0.508)
			(layers "B.Cu" "B.Mask" "B.Paste")
			(net "P1V8_NODE1")
		)
		(pad "2" smd rect
			(at 0.40005 0 270)
			(size 0.4572 0.508)
			(layers "B.Cu" "B.Mask" "B.Paste")
			(net "P1V8_SATA_VAA2_1_NODE1")
		)
	)
	(footprint ""
		(layer "B.Cu")
		(at 63.0555 -79.166466 -90)
		(property "Reference" "C68"
			(at 32.206946 14.38783 270)
			(unlocked yes)
			(layer "B.SilkS")
			(effects
				(font
					(size 0.7874 0.5842)
					(thickness 0.1524)
				)
				(justify left mirror)
			)
		)
		(property "Value" ""
			(at 0 0 90)
			(layer "B.Fab")
			(effects
				(font
					(size 1.27 1.27)
				)
				(justify mirror)
			)
		)
		(duplicate_pad_numbers_are_jumpers no)
		(fp_line
			(start -0.7874 0.4064)
			(end 0.7874 0.4064)
			(stroke
				(width 0.1524)
				(type default)
			)
			(layer "B.SilkS")
		)
		(fp_line
			(start 0.7874 0.4064)
			(end 0.7874 -0.4064)
			(stroke
				(width 0.1524)
				(type default)
			)
			(layer "B.SilkS")
		)
		(fp_line
			(start 0 0.381)
			(end 0 -0.381)
			(stroke
				(width 0.1524)
				(type default)
			)
			(layer "B.SilkS")
		)
		(fp_line
			(start -0.7874 -0.4064)
			(end -0.7874 0.4064)
			(stroke
				(width 0.1524)
				(type default)
			)
			(layer "B.SilkS")
		)
		(fp_line
			(start 0.7874 -0.4064)
			(end -0.7874 -0.4064)
			(stroke
				(width 0.1524)
				(type default)
			)
			(layer "B.SilkS")
		)
		(fp_poly
			(pts
				(xy 0.5334 0.254) (xy 0.635 0.254) (xy 0.635 0.2286) (xy 0.635 -0.254) (xy 0.5334 -0.254) (xy 0.5334 -0.2794)
				(xy -0.5334 -0.2794) (xy -0.5334 -0.254) (xy -0.635 -0.254) (xy -0.635 0.254) (xy -0.5334 0.254)
				(xy -0.5334 0.2794) (xy 0.508 0.2794) (xy 0.5334 0.2794)
			)
			(stroke
				(width 0)
				(type default)
			)
			(fill no)
			(layer "B.CrtYd")
		)
		(pad "1" smd rect
			(at -0.40005 0 90)
			(size 0.4572 0.508)
			(layers "B.Cu" "B.Mask" "B.Paste")
			(net "PV_VCCP_NODE1")
		)
		(pad "2" smd rect
			(at 0.40005 0 90)
			(size 0.4572 0.508)
			(layers "B.Cu" "B.Mask" "B.Paste")
			(net "GND")
		)
	)
	(footprint ""
		(layer "B.Cu")
		(at 117.45976 -185.205624 90)
		(property "Reference" "R878"
			(at 3.957828 0.468122 270)
			(unlocked yes)
			(layer "B.SilkS")
			(effects
				(font
					(size 0.7874 0.5842)
					(thickness 0.1524)
				)
				(justify left mirror)
			)
		)
		(property "Value" ""
			(at 0 0 90)
			(layer "B.Fab")
			(effects
				(font
					(size 1.27 1.27)
				)
				(justify mirror)
			)
		)
		(duplicate_pad_numbers_are_jumpers no)
		(fp_line
			(start 0.7874 -0.406146)
			(end -0.7874 -0.406146)
			(stroke
				(width 0.1524)
				(type default)
			)
			(layer "B.SilkS")
		)
		(fp_line
			(start -0.7874 -0.406146)
			(end -0.7874 0.406146)
			(stroke
				(width 0.1524)
				(type default)
			)
			(layer "B.SilkS")
		)
		(fp_line
			(start 0.7874 0.406146)
			(end 0.7874 -0.406146)
			(stroke
				(width 0.1524)
				(type default)
			)
			(layer "B.SilkS")
		)
		(fp_line
			(start -0.7874 0.406146)
			(end 0.7874 0.406146)
			(stroke
				(width 0.1524)
				(type default)
			)
			(layer "B.SilkS")
		)
		(fp_poly
			(pts
				(xy 0.508 0.2794) (xy 0.508 0.2286) (xy 0.635 0.2286) (xy 0.635 -0.254) (xy 0.5334 -0.254) (xy 0.5334 -0.2794)
				(xy -0.5334 -0.2794) (xy -0.5334 -0.254) (xy -0.635 -0.254) (xy -0.635 0.254) (xy -0.5334 0.254)
				(xy -0.5334 0.2794)
			)
			(stroke
				(width 0)
				(type default)
			)
			(fill no)
			(layer "B.CrtYd")
		)
		(pad "1" smd rect
			(at -0.40005 0 270)
			(size 0.4572 0.508)
			(layers "B.Cu" "B.Mask" "B.Paste")
			(net "T7_NODE3_EN")
		)
		(pad "2" smd rect
			(at 0.40005 0 270)
			(size 0.4572 0.508)
			(layers "B.Cu" "B.Mask" "B.Paste")
			(net "T7_NODE3_EN_R")
		)
	)
	(footprint ""
		(layer "B.Cu")
		(at 52.72786 -76.312776)
		(property "Reference" "R42"
			(at -14.47038 31.371794 0)
			(unlocked yes)
			(layer "B.SilkS")
			(effects
				(font
					(size 0.7874 0.5842)
					(thickness 0.1524)
				)
				(justify left mirror)
			)
		)
		(property "Value" ""
			(at 0 0 0)
			(layer "B.Fab")
			(effects
				(font
					(size 1.27 1.27)
				)
				(justify mirror)
			)
		)
		(duplicate_pad_numbers_are_jumpers no)
		(fp_line
			(start -0.7874 -0.4064)
			(end -0.7874 0.4064)
			(stroke
				(width 0.1524)
				(type default)
			)
			(layer "B.SilkS")
		)
		(fp_line
			(start -0.7874 0.4064)
			(end 0.7874 0.4064)
			(stroke
				(width 0.1524)
				(type default)
			)
			(layer "B.SilkS")
		)
		(fp_line
			(start 0.7874 -0.4064)
			(end -0.7874 -0.4064)
			(stroke
				(width 0.1524)
				(type default)
			)
			(layer "B.SilkS")
		)
		(fp_line
			(start 0.7874 0.4064)
			(end 0.7874 -0.4064)
			(stroke
				(width 0.1524)
				(type default)
			)
			(layer "B.SilkS")
		)
		(fp_poly
			(pts
				(xy 0.508 0.2794) (xy 0.508 0.2286) (xy 0.635 0.2286) (xy 0.635 -0.254) (xy 0.5334 -0.254) (xy 0.5334 -0.2794)
				(xy -0.5334 -0.2794) (xy -0.5334 -0.254) (xy -0.635 -0.254) (xy -0.635 0.254) (xy -0.5334 0.254)
				(xy -0.5334 0.2794)
			)
			(stroke
				(width 0)
				(type default)
			)
			(fill no)
			(layer "B.CrtYd")
		)
		(pad "1" smd rect
			(at -0.40005 0 180)
			(size 0.4572 0.508)
			(layers "B.Cu" "B.Mask" "B.Paste")
			(net "PD_CPU_NODE1_AJ23")
		)
		(pad "2" smd rect
			(at 0.40005 0 180)
			(size 0.4572 0.508)
			(layers "B.Cu" "B.Mask" "B.Paste")
			(net "GND")
		)
	)
	(footprint ""
		(layer "B.Cu")
		(at 47.10176 -181.992524 -90)
		(property "Reference" "C615"
			(at 3.618738 10.238994 270)
			(unlocked yes)
			(layer "B.SilkS")
			(effects
				(font
					(size 0.7874 0.5842)
					(thickness 0.1524)
				)
				(justify left mirror)
			)
		)
		(property "Value" ""
			(at 0 0 90)
			(layer "B.Fab")
			(effects
				(font
					(size 1.27 1.27)
				)
				(justify mirror)
			)
		)
		(duplicate_pad_numbers_are_jumpers no)
		(fp_line
			(start -0.7874 0.4064)
			(end 0.7874 0.4064)
			(stroke
				(width 0.1524)
				(type default)
			)
			(layer "B.SilkS")
		)
		(fp_line
			(start 0.7874 0.4064)
			(end 0.7874 -0.4064)
			(stroke
				(width 0.1524)
				(type default)
			)
			(layer "B.SilkS")
		)
		(fp_line
			(start 0 0.381)
			(end 0 -0.381)
			(stroke
				(width 0.1524)
				(type default)
			)
			(layer "B.SilkS")
		)
		(fp_line
			(start -0.7874 -0.4064)
			(end -0.7874 0.4064)
			(stroke
				(width 0.1524)
				(type default)
			)
			(layer "B.SilkS")
		)
		(fp_line
			(start 0.7874 -0.4064)
			(end -0.7874 -0.4064)
			(stroke
				(width 0.1524)
				(type default)
			)
			(layer "B.SilkS")
		)
		(fp_poly
			(pts
				(xy 0.5334 0.254) (xy 0.635 0.254) (xy 0.635 0.2286) (xy 0.635 -0.254) (xy 0.5334 -0.254) (xy 0.5334 -0.2794)
				(xy -0.5334 -0.2794) (xy -0.5334 -0.254) (xy -0.635 -0.254) (xy -0.635 0.254) (xy -0.5334 0.254)
				(xy -0.5334 0.2794) (xy 0.508 0.2794) (xy 0.5334 0.2794)
			)
			(stroke
				(width 0)
				(type default)
			)
			(fill no)
			(layer "B.CrtYd")
		)
		(pad "1" smd rect
			(at -0.40005 0 90)
			(size 0.4572 0.508)
			(layers "B.Cu" "B.Mask" "B.Paste")
			(net "PSU6_DC_OK_R_BUF")
		)
		(pad "2" smd rect
			(at 0.40005 0 90)
			(size 0.4572 0.508)
			(layers "B.Cu" "B.Mask" "B.Paste")
			(net "GND")
		)
	)
	(footprint ""
		(layer "B.Cu")
		(at 135.36676 -187.872624 90)
		(property "Reference" "R956"
			(at 4.565396 -1.359154 270)
			(unlocked yes)
			(layer "B.SilkS")
			(effects
				(font
					(size 0.7874 0.5842)
					(thickness 0.1524)
				)
				(justify left mirror)
			)
		)
		(property "Value" ""
			(at 0 0 90)
			(layer "B.Fab")
			(effects
				(font
					(size 1.27 1.27)
				)
				(justify mirror)
			)
		)
		(duplicate_pad_numbers_are_jumpers no)
		(fp_line
			(start 0.7874 -0.4064)
			(end -0.7874 -0.4064)
			(stroke
				(width 0.1524)
				(type default)
			)
			(layer "B.SilkS")
		)
		(fp_line
			(start -0.7874 -0.4064)
			(end -0.7874 0.4064)
			(stroke
				(width 0.1524)
				(type default)
			)
			(layer "B.SilkS")
		)
		(fp_line
			(start 0.7874 0.4064)
			(end 0.7874 -0.4064)
			(stroke
				(width 0.1524)
				(type default)
			)
			(layer "B.SilkS")
		)
		(fp_line
			(start -0.7874 0.4064)
			(end 0.7874 0.4064)
			(stroke
				(width 0.1524)
				(type default)
			)
			(layer "B.SilkS")
		)
		(fp_poly
			(pts
				(xy 0.508 0.2794) (xy 0.508 0.2286) (xy 0.635 0.2286) (xy 0.635 -0.254) (xy 0.5334 -0.254) (xy 0.5334 -0.2794)
				(xy -0.5334 -0.2794) (xy -0.5334 -0.254) (xy -0.635 -0.254) (xy -0.635 0.254) (xy -0.5334 0.254)
				(xy -0.5334 0.2794)
			)
			(stroke
				(width 0)
				(type default)
			)
			(fill no)
			(layer "B.CrtYd")
		)
		(pad "1" smd rect
			(at -0.40005 0 270)
			(size 0.4572 0.508)
			(layers "B.Cu" "B.Mask" "B.Paste")
			(net "UART_T9_NODE1_RXD")
		)
		(pad "2" smd rect
			(at 0.40005 0 270)
			(size 0.4572 0.508)
			(layers "B.Cu" "B.Mask" "B.Paste")
			(net "UART_T9_NODE1_RXD_R")
		)
	)
	(footprint ""
		(layer "B.Cu")
		(at 62.22873 -137.106406)
		(property "Reference" "C280"
			(at -40.681148 52.897278 0)
			(unlocked yes)
			(layer "B.SilkS")
			(effects
				(font
					(size 0.7874 0.5842)
					(thickness 0.1524)
				)
				(justify left mirror)
			)
		)
		(property "Value" ""
			(at 0 0 0)
			(layer "B.Fab")
			(effects
				(font
					(size 1.27 1.27)
				)
				(justify mirror)
			)
		)
		(duplicate_pad_numbers_are_jumpers no)
		(fp_line
			(start -0.7874 -0.4064)
			(end -0.7874 0.4064)
			(stroke
				(width 0.1524)
				(type default)
			)
			(layer "B.SilkS")
		)
		(fp_line
			(start -0.7874 0.4064)
			(end 0.7874 0.4064)
			(stroke
				(width 0.1524)
				(type default)
			)
			(layer "B.SilkS")
		)
		(fp_line
			(start 0 0.381)
			(end 0 -0.381)
			(stroke
				(width 0.1524)
				(type default)
			)
			(layer "B.SilkS")
		)
		(fp_line
			(start 0.7874 -0.4064)
			(end -0.7874 -0.4064)
			(stroke
				(width 0.1524)
				(type default)
			)
			(layer "B.SilkS")
		)
		(fp_line
			(start 0.7874 0.4064)
			(end 0.7874 -0.4064)
			(stroke
				(width 0.1524)
				(type default)
			)
			(layer "B.SilkS")
		)
		(fp_poly
			(pts
				(xy 0.5334 0.254) (xy 0.635 0.254) (xy 0.635 0.2286) (xy 0.635 -0.254) (xy 0.5334 -0.254) (xy 0.5334 -0.2794)
				(xy -0.5334 -0.2794) (xy -0.5334 -0.254) (xy -0.635 -0.254) (xy -0.635 0.254) (xy -0.5334 0.254)
				(xy -0.5334 0.2794) (xy 0.508 0.2794) (xy 0.5334 0.2794)
			)
			(stroke
				(width 0)
				(type default)
			)
			(fill no)
			(layer "B.CrtYd")
		)
		(pad "1" smd rect
			(at -0.40005 0 180)
			(size 0.4572 0.508)
			(layers "B.Cu" "B.Mask" "B.Paste")
			(net "P3V3_NODE1")
		)
		(pad "2" smd rect
			(at 0.40005 0 180)
			(size 0.4572 0.508)
			(layers "B.Cu" "B.Mask" "B.Paste")
			(net "GND")
		)
	)
	(footprint ""
		(layer "B.Cu")
		(at 73.207372 -80.514698 90)
		(property "Reference" "C69"
			(at -32.276034 -14.610842 270)
			(unlocked yes)
			(layer "B.SilkS")
			(effects
				(font
					(size 0.7874 0.5842)
					(thickness 0.1524)
				)
				(justify left mirror)
			)
		)
		(property "Value" ""
			(at 0 0 90)
			(layer "B.Fab")
			(effects
				(font
					(size 1.27 1.27)
				)
				(justify mirror)
			)
		)
		(duplicate_pad_numbers_are_jumpers no)
		(fp_line
			(start 0.7874 -0.4064)
			(end -0.7874 -0.4064)
			(stroke
				(width 0.1524)
				(type default)
			)
			(layer "B.SilkS")
		)
		(fp_line
			(start -0.7874 -0.4064)
			(end -0.7874 0.4064)
			(stroke
				(width 0.1524)
				(type default)
			)
			(layer "B.SilkS")
		)
		(fp_line
			(start 0 0.381)
			(end 0 -0.381)
			(stroke
				(width 0.1524)
				(type default)
			)
			(layer "B.SilkS")
		)
		(fp_line
			(start 0.7874 0.4064)
			(end 0.7874 -0.4064)
			(stroke
				(width 0.1524)
				(type default)
			)
			(layer "B.SilkS")
		)
		(fp_line
			(start -0.7874 0.4064)
			(end 0.7874 0.4064)
			(stroke
				(width 0.1524)
				(type default)
			)
			(layer "B.SilkS")
		)
		(fp_poly
			(pts
				(xy 0.5334 0.254) (xy 0.635 0.254) (xy 0.635 0.2286) (xy 0.635 -0.254) (xy 0.5334 -0.254) (xy 0.5334 -0.2794)
				(xy -0.5334 -0.2794) (xy -0.5334 -0.254) (xy -0.635 -0.254) (xy -0.635 0.254) (xy -0.5334 0.254)
				(xy -0.5334 0.2794) (xy 0.508 0.2794) (xy 0.5334 0.2794)
			)
			(stroke
				(width 0)
				(type default)
			)
			(fill no)
			(layer "B.CrtYd")
		)
		(pad "1" smd rect
			(at -0.40005 0 270)
			(size 0.4572 0.508)
			(layers "B.Cu" "B.Mask" "B.Paste")
			(net "PV_VCCP_NODE1")
		)
		(pad "2" smd rect
			(at 0.40005 0 270)
			(size 0.4572 0.508)
			(layers "B.Cu" "B.Mask" "B.Paste")
			(net "GND")
		)
	)
	(footprint ""
		(layer "B.Cu")
		(at 88.77935 -77.749654)
		(property "Reference" "R171"
			(at -1.91516 9.670288 0)
			(unlocked yes)
			(layer "B.SilkS")
			(effects
				(font
					(size 0.7874 0.5842)
					(thickness 0.1524)
				)
				(justify left mirror)
			)
		)
		(property "Value" ""
			(at 0 0 0)
			(layer "B.Fab")
			(effects
				(font
					(size 1.27 1.27)
				)
				(justify mirror)
			)
		)
		(duplicate_pad_numbers_are_jumpers no)
		(fp_line
			(start -0.7874 -0.4064)
			(end -0.7874 0.4064)
			(stroke
				(width 0.1524)
				(type default)
			)
			(layer "B.SilkS")
		)
		(fp_line
			(start -0.7874 0.4064)
			(end 0.7874 0.4064)
			(stroke
				(width 0.1524)
				(type default)
			)
			(layer "B.SilkS")
		)
		(fp_line
			(start 0.7874 -0.4064)
			(end -0.7874 -0.4064)
			(stroke
				(width 0.1524)
				(type default)
			)
			(layer "B.SilkS")
		)
		(fp_line
			(start 0.7874 0.4064)
			(end 0.7874 -0.4064)
			(stroke
				(width 0.1524)
				(type default)
			)
			(layer "B.SilkS")
		)
		(fp_poly
			(pts
				(xy 0.508 0.2794) (xy 0.508 0.2286) (xy 0.635 0.2286) (xy 0.635 -0.254) (xy 0.5334 -0.254) (xy 0.5334 -0.2794)
				(xy -0.5334 -0.2794) (xy -0.5334 -0.254) (xy -0.635 -0.254) (xy -0.635 0.254) (xy -0.5334 0.254)
				(xy -0.5334 0.2794)
			)
			(stroke
				(width 0)
				(type default)
			)
			(fill no)
			(layer "B.CrtYd")
		)
		(pad "1" smd rect
			(at -0.40005 0 180)
			(size 0.4572 0.508)
			(layers "B.Cu" "B.Mask" "B.Paste")
			(net "PU_CPU_NODE1_MEM_SPEED0")
		)
		(pad "2" smd rect
			(at 0.40005 0 180)
			(size 0.4572 0.508)
			(layers "B.Cu" "B.Mask" "B.Paste")
			(net "P1V05_SUS_NODE1")
		)
	)
	(footprint ""
		(layer "B.Cu")
		(at 171.180252 -103.32339 180)
		(property "Reference" "C377"
			(at -7.681722 -0.220726 0)
			(unlocked yes)
			(layer "B.SilkS")
			(effects
				(font
					(size 0.7874 0.5842)
					(thickness 0.1524)
				)
				(justify left mirror)
			)
		)
		(property "Value" ""
			(at 0 0 0)
			(layer "B.Fab")
			(effects
				(font
					(size 1.27 1.27)
				)
				(justify mirror)
			)
		)
		(duplicate_pad_numbers_are_jumpers no)
		(fp_line
			(start 0.7874 0.4064)
			(end 0.7874 -0.4064)
			(stroke
				(width 0.1524)
				(type default)
			)
			(layer "B.SilkS")
		)
		(fp_line
			(start 0.7874 -0.4064)
			(end -0.7874 -0.4064)
			(stroke
				(width 0.1524)
				(type default)
			)
			(layer "B.SilkS")
		)
		(fp_line
			(start 0 0.381)
			(end 0 -0.381)
			(stroke
				(width 0.1524)
				(type default)
			)
			(layer "B.SilkS")
		)
		(fp_line
			(start -0.7874 0.4064)
			(end 0.7874 0.4064)
			(stroke
				(width 0.1524)
				(type default)
			)
			(layer "B.SilkS")
		)
		(fp_line
			(start -0.7874 -0.4064)
			(end -0.7874 0.4064)
			(stroke
				(width 0.1524)
				(type default)
			)
			(layer "B.SilkS")
		)
		(fp_poly
			(pts
				(xy 0.5334 0.254) (xy 0.635 0.254) (xy 0.635 0.2286) (xy 0.635 -0.254) (xy 0.5334 -0.254) (xy 0.5334 -0.2794)
				(xy -0.5334 -0.2794) (xy -0.5334 -0.254) (xy -0.635 -0.254) (xy -0.635 0.254) (xy -0.5334 0.254)
				(xy -0.5334 0.2794) (xy 0.508 0.2794) (xy 0.5334 0.2794)
			)
			(stroke
				(width 0)
				(type default)
			)
			(fill no)
			(layer "B.CrtYd")
		)
		(pad "1" smd rect
			(at -0.40005 0)
			(size 0.4572 0.508)
			(layers "B.Cu" "B.Mask" "B.Paste")
			(net "P3V3_NODE1")
		)
		(pad "2" smd rect
			(at 0.40005 0)
			(size 0.4572 0.508)
			(layers "B.Cu" "B.Mask" "B.Paste")
			(net "GND")
		)
	)
)
